(kicad_pcb
	(version 20260206)
	(generator "pcbnew")
	(generator_version "10.0")
	(general
		(thickness 1.6)
		(legacy_teardrops no)
	)
	(paper "A4")
	(title_block
		(title "Wiwynn_Tioga_Pass_MB.brd")
		(comment 1 "Tioga Pass / footprints 3048-3052 of 4770")
	)
	(layers
		(0 "F.Cu" signal "TOP")
		(4 "In1.Cu" signal "L2GND")
		(6 "In2.Cu" signal "L3")
		(8 "In3.Cu" signal "L4GND")
		(10 "In4.Cu" signal "L5")
		(12 "In5.Cu" signal "L6GND")
		(14 "In6.Cu" signal "L7VCC")
		(16 "In7.Cu" signal "L8VCC")
		(18 "In8.Cu" signal "L9GND")
		(20 "In9.Cu" signal "L10")
		(22 "In10.Cu" signal "L11GND")
		(24 "In11.Cu" signal "L12")
		(26 "In12.Cu" signal "L13GND")
		(2 "B.Cu" signal "BOTTOM")
		(9 "F.Adhes" user "F.Adhesive")
		(11 "B.Adhes" user "B.Adhesive")
		(13 "F.Paste" user "Package Geometry/Pastemask Top")
		(15 "B.Paste" user "Package Geometry/Pastemask Bottom")
		(5 "F.SilkS" user "Ref Des/Silkscreen Top")
		(7 "B.SilkS" user "Ref Des/Silkscreen Bottom")
		(1 "F.Mask" user "Board Geometry/Soldermask Top")
		(3 "B.Mask" user "Board Geometry/Soldermask Bottom")
		(17 "Dwgs.User" user "User.Drawings")
		(19 "Cmts.User" user "User.Comments")
		(21 "Eco1.User" user "User.Eco1")
		(23 "Eco2.User" user "User.Eco2")
		(25 "Edge.Cuts" user "Board Geometry/Outline")
		(27 "Margin" user)
		(31 "F.CrtYd" user "Package Geometry/Place Bound Top")
		(29 "B.CrtYd" user "Package Geometry/Place Bound Bottom")
		(35 "F.Fab" user "Ref Des/Assembly Top")
		(33 "B.Fab" user "Ref Des/Assembly Bottom")
	)
	(footprint ""
		(layer "B.Cu")
		(at 425.196 -141.986)
		(property "Reference" "C2L41"
			(at 0 0 0)
			(layer "B.SilkS")
			(hide yes)
			(effects
				(font
					(size 1.27 1.27)
				)
				(justify mirror)
			)
		)
		(property "Value" ""
			(at 0 0 0)
			(layer "B.Fab")
			(effects
				(font
					(size 1.27 1.27)
				)
				(justify mirror)
			)
		)
		(duplicate_pad_numbers_are_jumpers no)
		(fp_poly
			(pts
				(xy -0.3048 -0.1016) (xy -0.3048 0.9906) (xy 0.3048 0.9906) (xy 0.3048 -0.1016)
			)
			(stroke
				(width 0)
				(type default)
			)
			(fill no)
			(layer "B.CrtYd")
		)
		(fp_line
			(start -0.3048 -0.1016)
			(end 0.3048 -0.1016)
			(stroke
				(width 0.1)
				(type default)
			)
			(layer "B.Fab")
		)
		(fp_line
			(start -0.3048 0.9906)
			(end -0.3048 -0.1016)
			(stroke
				(width 0.1)
				(type default)
			)
			(layer "B.Fab")
		)
		(fp_line
			(start 0.3048 -0.1016)
			(end 0.3048 0.9906)
			(stroke
				(width 0.1)
				(type default)
			)
			(layer "B.Fab")
		)
		(fp_line
			(start 0.3048 0.9906)
			(end -0.3048 0.9906)
			(stroke
				(width 0.1)
				(type default)
			)
			(layer "B.Fab")
		)
		(pad "1" smd rect
			(at 0 0 180)
			(size 0.508 0.508)
			(layers "B.Cu" "B.Mask" "B.Paste")
			(net "SATA6G_P2_TX_C_DP")
		)
		(pad "2" smd rect
			(at 0 0.889 180)
			(size 0.508 0.508)
			(layers "B.Cu" "B.Mask" "B.Paste")
			(net "SATA6G_PCH_PCIE_UP_SATA_TXP<2>")
		)
		(zone
			(layer "B.Cu")
			(hatch none 0.5)
			(connect_pads
				(clearance 0)
			)
			(min_thickness 0.25)
			(keepout
				(tracks allowed)
				(vias not_allowed)
				(pads allowed)
				(copperpour not_allowed)
				(footprints allowed)
			)
			(placement
				(enabled no)
				(sheetname "")
			)
			(fill
				(thermal_gap 0.5)
				(thermal_bridge_width 0.5)
				(island_removal_mode 0)
			)
			(polygon
				(pts
					(xy 425.45 -141.732) (xy 424.942 -141.732) (xy 424.942 -141.351) (xy 425.45 -141.351)
				)
			)
		)
		(zone
			(layer "B.Cu")
			(hatch none 0.5)
			(connect_pads
				(clearance 0)
			)
			(min_thickness 0.25)
			(keepout
				(tracks not_allowed)
				(vias allowed)
				(pads allowed)
				(copperpour not_allowed)
				(footprints allowed)
			)
			(placement
				(enabled no)
				(sheetname "")
			)
			(fill
				(thermal_gap 0.5)
				(thermal_bridge_width 0.5)
				(island_removal_mode 0)
			)
			(polygon
				(pts
					(xy 425.45 -141.351) (xy 424.942 -141.351) (xy 424.942 -141.732) (xy 425.45 -141.732)
				)
			)
		)
	)
	(footprint ""
		(layer "B.Cu")
		(at 107.8611 -135.4074 90)
		(property "Reference" "C7M2"
			(at -1.848866 0.752348 90)
			(unlocked yes)
			(layer "B.SilkS")
			(effects
				(font
					(size 1.27 0.9652)
					(thickness 0.1524)
				)
				(justify mirror)
			)
		)
		(property "Value" ""
			(at 0 0 90)
			(layer "B.Fab")
			(effects
				(font
					(size 1.27 1.27)
				)
				(justify mirror)
			)
		)
		(duplicate_pad_numbers_are_jumpers no)
		(fp_rect
			(start 0.500126 1.598422)
			(end -0.500126 -0.201422)
			(stroke
				(width 0)
				(type default)
			)
			(fill no)
			(layer "B.CrtYd")
		)
		(fp_line
			(start 0.500126 -0.201422)
			(end -0.500126 -0.201422)
			(stroke
				(width 0.1)
				(type default)
			)
			(layer "B.Fab")
		)
		(fp_line
			(start -0.500126 -0.201422)
			(end -0.500126 1.598422)
			(stroke
				(width 0.1)
				(type default)
			)
			(layer "B.Fab")
		)
		(fp_line
			(start 0.500126 1.598422)
			(end 0.500126 -0.201422)
			(stroke
				(width 0.1)
				(type default)
			)
			(layer "B.Fab")
		)
		(fp_line
			(start -0.500126 1.598422)
			(end 0.500126 1.598422)
			(stroke
				(width 0.1)
				(type default)
			)
			(layer "B.Fab")
		)
		(pad "1" smd rect
			(at 0 0)
			(size 0.889 0.9906)
			(layers "B.Cu" "B.Mask" "B.Paste")
			(net "PVDDQ_KLM")
		)
		(pad "2" smd rect
			(at 0 1.397)
			(size 0.889 0.9906)
			(layers "B.Cu" "B.Mask" "B.Paste")
			(net "GND")
		)
		(zone
			(layer "B.Cu")
			(hatch none 0.5)
			(connect_pads
				(clearance 0)
			)
			(min_thickness 0.25)
			(keepout
				(tracks allowed)
				(vias not_allowed)
				(pads allowed)
				(copperpour not_allowed)
				(footprints allowed)
			)
			(placement
				(enabled no)
				(sheetname "")
			)
			(fill
				(thermal_gap 0.5)
				(thermal_bridge_width 0.5)
				(island_removal_mode 0)
			)
			(polygon
				(pts
					(xy 108.8136 -135.9027) (xy 108.3056 -135.9027) (xy 108.3056 -134.9121) (xy 108.8136 -134.9121)
				)
			)
		)
		(zone
			(layer "B.Cu")
			(hatch none 0.5)
			(connect_pads
				(clearance 0)
			)
			(min_thickness 0.25)
			(keepout
				(tracks not_allowed)
				(vias allowed)
				(pads allowed)
				(copperpour not_allowed)
				(footprints allowed)
			)
			(placement
				(enabled no)
				(sheetname "")
			)
			(fill
				(thermal_gap 0.5)
				(thermal_bridge_width 0.5)
				(island_removal_mode 0)
			)
			(polygon
				(pts
					(xy 108.8136 -135.9027) (xy 108.3056 -135.9027) (xy 108.3056 -134.9121) (xy 108.8136 -134.9121)
				)
			)
		)
	)
	(footprint ""
		(layer "B.Cu")
		(at 313.424062 -27.727148 -90)
		(property "Reference" "Q8D1"
			(at 0 -1.2065 270)
			(unlocked yes)
			(layer "B.SilkS")
			(effects
				(font
					(size 1.27 0.9652)
					(thickness 0.1524)
				)
				(justify left mirror)
			)
		)
		(property "Value" ""
			(at 0 0 90)
			(layer "B.Fab")
			(effects
				(font
					(size 1.27 1.27)
				)
				(justify mirror)
			)
		)
		(duplicate_pad_numbers_are_jumpers no)
		(fp_circle
			(center 0.848614 -0.6477)
			(end 0.848614 -0.7747)
			(stroke
				(width 0.254)
				(type default)
			)
			(fill no)
			(layer "B.SilkS")
		)
		(fp_poly
			(pts
				(xy -0.21463 -0.450088) (xy -1.56337 -0.450088) (xy -1.56337 1.75006) (xy -0.21463 1.75006)
			)
			(stroke
				(width 0)
				(type default)
			)
			(fill no)
			(layer "B.CrtYd")
		)
		(fp_line
			(start -1.56337 1.75006)
			(end -0.21463 1.75006)
			(stroke
				(width 0.1)
				(type default)
			)
			(layer "B.Fab")
		)
		(fp_line
			(start -0.21463 1.75006)
			(end -0.21463 -0.450088)
			(stroke
				(width 0.1)
				(type default)
			)
			(layer "B.Fab")
		)
		(fp_line
			(start -1.56337 -0.450088)
			(end -1.56337 1.75006)
			(stroke
				(width 0.1)
				(type default)
			)
			(layer "B.Fab")
		)
		(fp_line
			(start -0.21463 -0.450088)
			(end -1.56337 -0.450088)
			(stroke
				(width 0.1)
				(type default)
			)
			(layer "B.Fab")
		)
		(fp_circle
			(center 0.848614 -0.6477)
			(end 0.848614 -0.7747)
			(stroke
				(width 0.254)
				(type default)
			)
			(fill no)
			(layer "B.Fab")
		)
		(pad "1" smd rect
			(at 0 0 90)
			(size 1.016 0.381)
			(layers "B.Cu" "B.Mask" "B.Paste")
			(net "GND")
		)
		(pad "2" smd rect
			(at 0 0.649986 90)
			(size 1.016 0.381)
			(layers "B.Cu" "B.Mask" "B.Paste")
			(net "IRQ_DIMM_SAVE_LVT3")
		)
		(pad "3" smd rect
			(at 0 1.299972 90)
			(size 1.016 0.381)
			(layers "B.Cu" "B.Mask" "B.Paste")
			(net "IRQ_DIMM_SAVE_LVT3")
		)
		(pad "4" smd rect
			(at -1.778 1.299972 90)
			(size 1.016 0.381)
			(layers "B.Cu" "B.Mask" "B.Paste")
			(net "GND")
		)
		(pad "5" smd rect
			(at -1.778 0.649986 90)
			(size 1.016 0.381)
			(layers "B.Cu" "B.Mask" "B.Paste")
			(net "IRQ_DIMM_SAVE_R_N")
		)
		(pad "6" smd rect
			(at -1.778 0 90)
			(size 1.016 0.381)
			(layers "B.Cu" "B.Mask" "B.Paste")
			(net "IRQ_DIMM_SAVE_LVT3_N")
		)
	)
	(footprint ""
		(layer "B.Cu")
		(at 469.197944 -11.42492)
		(property "Reference" "R2U31"
			(at 0 0 0)
			(layer "B.SilkS")
			(hide yes)
			(effects
				(font
					(size 1.27 1.27)
				)
				(justify mirror)
			)
		)
		(property "Value" ""
			(at 0 0 0)
			(layer "B.Fab")
			(effects
				(font
					(size 1.27 1.27)
				)
				(justify mirror)
			)
		)
		(duplicate_pad_numbers_are_jumpers no)
		(fp_poly
			(pts
				(xy 0.2794 -0.1016) (xy -0.2794 -0.1016) (xy -0.2794 0.9906) (xy 0.2794 0.9906)
			)
			(stroke
				(width 0)
				(type default)
			)
			(fill no)
			(layer "B.CrtYd")
		)
		(fp_line
			(start -0.2794 -0.1016)
			(end 0.2794 -0.1016)
			(stroke
				(width 0.1)
				(type default)
			)
			(layer "B.Fab")
		)
		(fp_line
			(start -0.2794 0.9906)
			(end -0.2794 -0.1016)
			(stroke
				(width 0.1)
				(type default)
			)
			(layer "B.Fab")
		)
		(fp_line
			(start 0.2794 -0.1016)
			(end 0.2794 0.9906)
			(stroke
				(width 0.1)
				(type default)
			)
			(layer "B.Fab")
		)
		(fp_line
			(start 0.2794 0.9906)
			(end -0.2794 0.9906)
			(stroke
				(width 0.1)
				(type default)
			)
			(layer "B.Fab")
		)
		(pad "1" smd rect
			(at 0 0 180)
			(size 0.508 0.508)
			(layers "B.Cu" "B.Mask" "B.Paste")
			(net "SMB_SLOTX24_BMC_STBY_LVC3_SDA")
		)
		(pad "2" smd rect
			(at 0 0.889 180)
			(size 0.508 0.508)
			(layers "B.Cu" "B.Mask" "B.Paste")
			(net "SMB_SLOTX24_STBY_LVC3_SDA_R2")
		)
		(zone
			(layer "B.Cu")
			(hatch none 0.5)
			(connect_pads
				(clearance 0)
			)
			(min_thickness 0.25)
			(keepout
				(tracks allowed)
				(vias not_allowed)
				(pads allowed)
				(copperpour not_allowed)
				(footprints allowed)
			)
			(placement
				(enabled no)
				(sheetname "")
			)
			(fill
				(thermal_gap 0.5)
				(thermal_bridge_width 0.5)
				(island_removal_mode 0)
			)
			(polygon
				(pts
					(xy 469.451944 -11.17092) (xy 468.943944 -11.17092) (xy 468.943944 -10.78992) (xy 469.451944 -10.78992)
				)
			)
		)
		(zone
			(layer "B.Cu")
			(hatch none 0.5)
			(connect_pads
				(clearance 0)
			)
			(min_thickness 0.25)
			(keepout
				(tracks not_allowed)
				(vias allowed)
				(pads allowed)
				(copperpour not_allowed)
				(footprints allowed)
			)
			(placement
				(enabled no)
				(sheetname "")
			)
			(fill
				(thermal_gap 0.5)
				(thermal_bridge_width 0.5)
				(island_removal_mode 0)
			)
			(polygon
				(pts
					(xy 469.451944 -10.78992) (xy 468.943944 -10.78992) (xy 468.943944 -11.17092) (xy 469.451944 -11.17092)
				)
			)
		)
	)
	(footprint ""
		(layer "B.Cu")
		(at 338.76996 -77.694536)
		(property "Reference" "C3P10"
			(at 0 0 0)
			(layer "B.SilkS")
			(hide yes)
			(effects
				(font
					(size 1.27 1.27)
				)
				(justify mirror)
			)
		)
		(property "Value" ""
			(at 0 0 0)
			(layer "B.Fab")
			(effects
				(font
					(size 1.27 1.27)
				)
				(justify mirror)
			)
		)
		(duplicate_pad_numbers_are_jumpers no)
		(fp_poly
			(pts
				(xy -0.3048 -0.1016) (xy -0.3048 0.9906) (xy 0.3048 0.9906) (xy 0.3048 -0.1016)
			)
			(stroke
				(width 0)
				(type default)
			)
			(fill no)
			(layer "B.CrtYd")
		)
		(fp_line
			(start -0.3048 -0.1016)
			(end 0.3048 -0.1016)
			(stroke
				(width 0.1)
				(type default)
			)
			(layer "B.Fab")
		)
		(fp_line
			(start -0.3048 0.9906)
			(end -0.3048 -0.1016)
			(stroke
				(width 0.1)
				(type default)
			)
			(layer "B.Fab")
		)
		(fp_line
			(start 0.3048 -0.1016)
			(end 0.3048 0.9906)
			(stroke
				(width 0.1)
				(type default)
			)
			(layer "B.Fab")
		)
		(fp_line
			(start 0.3048 0.9906)
			(end -0.3048 0.9906)
			(stroke
				(width 0.1)
				(type default)
			)
			(layer "B.Fab")
		)
		(pad "1" smd rect
			(at 0 0 180)
			(size 0.508 0.508)
			(layers "B.Cu" "B.Mask" "B.Paste")
			(net "P3E_CPU0_PE1_SS_TXP<0>")
		)
		(pad "2" smd rect
			(at 0 0.889 180)
			(size 0.508 0.508)
			(layers "B.Cu" "B.Mask" "B.Paste")
			(net "P3E_CPU0_PE1_SS_C_TXP<0>")
		)
		(zone
			(layer "B.Cu")
			(hatch none 0.5)
			(connect_pads
				(clearance 0)
			)
			(min_thickness 0.25)
			(keepout
				(tracks allowed)
				(vias not_allowed)
				(pads allowed)
				(copperpour not_allowed)
				(footprints allowed)
			)
			(placement
				(enabled no)
				(sheetname "")
			)
			(fill
				(thermal_gap 0.5)
				(thermal_bridge_width 0.5)
				(island_removal_mode 0)
			)
			(polygon
				(pts
					(xy 339.02396 -77.440536) (xy 338.51596 -77.440536) (xy 338.51596 -77.059536) (xy 339.02396 -77.059536)
				)
			)
		)
		(zone
			(layer "B.Cu")
			(hatch none 0.5)
			(connect_pads
				(clearance 0)
			)
			(min_thickness 0.25)
			(keepout
				(tracks not_allowed)
				(vias allowed)
				(pads allowed)
				(copperpour not_allowed)
				(footprints allowed)
			)
			(placement
				(enabled no)
				(sheetname "")
			)
			(fill
				(thermal_gap 0.5)
				(thermal_bridge_width 0.5)
				(island_removal_mode 0)
			)
			(polygon
				(pts
					(xy 339.02396 -77.059536) (xy 338.51596 -77.059536) (xy 338.51596 -77.440536) (xy 339.02396 -77.440536)
				)
			)
		)
	)
)
